FILE_TYPE = CONNECTIVITY;
{Allegro Design Entry HDL 17.2-2016 S081 (4005846) 1/11/2022}
"PAGE_NUMBER" = 54;
0"NC";
1"P3V3_AUX\g";
2"P3V3_LDO\g";
3"P1V8_AUX\g";
4"P3V3_AUX\g";
5"P5V_AUX\g";
6"GND\g";
7"GND\g";
8"GND\g";
9"GND\g";
10"GND\g";
11"GND\g";
12"GND\g";
13"GND\g";
14"EN_P1V8_R";
15"EN_P1V8";
16"PWRGD_P2V5_AUX_R3";
17"PWRGD_P1V8_AUX_R";
18"PWRGD_P3V3_RGM_R2";
19"PWRGD_P3V3_RGM";
20"PWRGD_P1V8_AUX_R3";
21"PWRGD_P1V8_AUX";
22"EN_P1V8";
23"PWRGD_P5V_AUX";
24"U41_ADJ";
%"Q_CAP"
"1","(-1075,1425)","0","pure_quanta","I100";
;
MATERIAL"EMPTY"
TOLERANCE"10%"
VOLTAGE"50V"
VALUE"0.001UF"
PACK_TYPE"C0402"
PART_NUMBER"CH30106KB19"
CDS_LIB"pure_quanta"
LOCATION"C154"
$SEC"1"
CDS_SEC"1";
"B"
$PN"2"9;
"A"
$PN"1"17;
%"UNIVERSAL_GND"
"1","(-1075,1225)","0","logical_power","I101";
;
HDL_POWER"GND"
CDS_LIB"logical_power";
"A"9;
%"Q_RES"
"1","(-1625,2175)","0","pure_quanta","I102";
;
VALUE"0"
MATERIAL"CHIP"
PART_NUMBER"CS00002JB13"
TOLERANCE"5%"
WATTAGE"1/16W"
PACK_TYPE"0402LF"
CDS_LIB"pure_quanta"
LOCATION"R393"
$SEC"1"
CDS_SEC"1";
"B"
$PN"2"14;
"A"
$PN"1"15;
%"Q_CAP"
"1","(1850,2000)","0","pure_quanta","I104";
;
TOLERANCE"10%"
VOLTAGE"25V"
MATERIAL"X6S"
VALUE"10UF"
PART_NUMBER"CH6104KEA00"
PACK_TYPE"C0805"
CDS_LIB"pure_quanta"
$LOCATION"C142"
CDS_LOCATION"C142"
$SEC"1"
CDS_SEC"1";
"B"
$PN"2"12;
"A"
$PN"1"3;
%"Q_CAP"
"1","(2500,2000)","0","pure_quanta","I105";
;
TOLERANCE"10%"
PACK_TYPE"0402"
VALUE"0.1UF"
MATERIAL"X7R"
VOLTAGE"25V"
PART_NUMBER"CH4104K1B00"
CDS_LIB"pure_quanta"
$LOCATION"C294"
CDS_LOCATION"C294"
$SEC"1"
CDS_SEC"1";
"B"
$PN"2"12;
"A"
$PN"1"3;
%"Q_CAP"
"1","(1050,3025)","0","pure_quanta","I106";
;
TOLERANCE"10%"
MATERIAL"X6S"
VOLTAGE"25V"
VALUE"10UF"
PART_NUMBER"CH6104KEA00"
PACK_TYPE"C0805"
CDS_LIB"pure_quanta"
$LOCATION"C293"
CDS_LOCATION"C293"
$SEC"1"
CDS_SEC"1";
"B"
$PN"2"13;
"A"
$PN"1"4;
%"Q_CAP"
"1","(-1000,2850)","0","pure_quanta","I107";
;
VALUE"1UF"
VOLTAGE"25V"
TOLERANCE"10%"
MATERIAL"X6S"
PART_NUMBER"CH5104KEB02"
PACK_TYPE"C0402"
CDS_LIB"pure_quanta"
$LOCATION"C292"
CDS_LOCATION"C292"
$SEC"1"
CDS_SEC"1";
"B"
$PN"2"11;
"A"
$PN"1"5;
%"Q_RES"
"2","(-725,1850)","0","pure_quanta","I108";
;
PACK_TYPE"0402LF"
TOLERANCE"1%"
VALUE"10K"
PART_NUMBER"CS31002FB08"
MATERIAL"CHIP"
WATTAGE"1/16W"
CDS_LIB"pure_quanta"
$LOCATION"R406"
CDS_LOCATION"R406"
$SEC"1"
CDS_SEC"1";
"A"
$PN"1"1;
"B"
$PN"2"17;
%"UNIVERSAL_GND"
"1","(350,-950)","0","logical_power","I111";
;
CDS_LIB"logical_power"
HDL_POWER"GND";
"A"7;
%"Q_CAP"
"1","(1500,50)","2","pure_quanta","I112";
;
VOLTAGE"25V"
VALUE"0.1UF"
TOLERANCE"10%"
MATERIAL"X7R"
PACK_TYPE"0402"
PART_NUMBER"CH4104K1B00"
CDS_LIB"pure_quanta"
$LOCATION"C298"
CDS_LOCATION"C298"
$SEC"1"
CDS_SEC"1";
"B"
$PN"2"8;
"A"
$PN"1"2;
%"UNIVERSAL_GND"
"1","(1500,-175)","0","logical_power","I114";
;
CDS_LIB"logical_power"
HDL_POWER"GND";
"A"8;
%"MC74VHC1G32DTT1G"
"1","(975,-600)","0","pure_quanta","I116";
;
MATERIAL"IC"
PART_TYPE"SMLF"
VALUE"MC74VHC1G32DTT1G"
PART_NUMBER"AL001G32031"
NEEDS_NO_SIZE"TRUE"
CDS_LMAN_SYM_OUTLINE"-400,275,400,-275"
CDS_LIB"pure_quanta"
$LOCATION"U49"
CDS_LOCATION"U49"
$SEC"1"
CDS_SEC"1";
"VCC"
$PN"5"2;
"GND"
$PN"3"7;
"IN_A"
$PN"2"18;
"IN_B"
$PN"1"23;
"OUT_Y"
$PN"4"22;
%"Q_CAP"
"1","(-375,-825)","0","pure_quanta","I130";
;
VALUE"1UF"
VOLTAGE"25V"
PART_NUMBER"CH5104KEB02"
PACK_TYPE"C0402"
MATERIAL"X6S"
TOLERANCE"10%"
CDS_LIB"pure_quanta"
$LOCATION"C310"
CDS_LOCATION"C310"
$SEC"1"
CDS_SEC"1";
"B"
$PN"2"6;
"A"
$PN"1"18;
%"UNIVERSAL_GND"
"1","(-375,-1050)","0","logical_power","I131";
;
HDL_POWER"GND"
CDS_LIB"logical_power";
"A"6;
%"Q_RES"
"1","(-625,-625)","0","pure_quanta","I132";
;
PACK_TYPE"0402LF"
PART_NUMBER"CS11002FB07"
TOLERANCE"1%"
VALUE"100"
MATERIAL"CHIP"
WATTAGE"1/16W"
CDS_LIB"pure_quanta"
$LOCATION"R530"
CDS_LOCATION"R530"
$SEC"1"
CDS_SEC"1";
"B"
$PN"2"18;
"A"
$PN"1"19;
%"Q_RES"
"1","(-1625,2450)","0","pure_quanta","I137";
;
PACK_TYPE"0402LF"
WATTAGE"1/16W"
VALUE"0"
TOLERANCE"5%"
MATERIAL"EMPTY"
PART_NUMBER"CS00002JB13"
CDS_LIB"pure_quanta"
$LOCATION"R875"
CDS_LOCATION"R875"
$SEC"1"
CDS_SEC"1";
"B"
$PN"2"14;
"A"
$PN"1"16;
%"Q_RES"
"1","(-2025,1800)","0","pure_quanta","I139";
;
MATERIAL"EMPTY"
VALUE"0"
PACK_TYPE"0402LF"
PART_NUMBER"CS00002JB13"
WATTAGE"1/16W"
TOLERANCE"5%"
CDS_LIB"pure_quanta"
$LOCATION"R874"
CDS_LOCATION"R874"
$SEC"1"
CDS_SEC"1";
"B"
$PN"2"17;
"A"
$PN"1"20;
%"UNIVERSAL_POWER"
"1","(1500,300)","0","logical_power","I141";
;
HDL_POWER"P3V3_LDO"
CDS_LIB"logical_power";
"A"2;
%"UNIVERSAL_GND"
"1","(550,1350)","0","logical_power","I54";
;
HDL_POWER"GND"
CDS_LIB"logical_power";
"A"10;
%"UNIVERSAL_GND"
"1","(-1000,2525)","0","logical_power","I58";
;
HDL_POWER"GND"
CDS_LIB"logical_power";
"A"11;
%"VCCAUX15"
"1","(-1000,3275)","0","logical_power","I60";
;
HDL_POWER"P5V_AUX"
CDS_LIB"logical_power";
"A"5;
%"UNIVERSAL_GND"
"1","(1850,1575)","0","logical_power","I61";
;
HDL_POWER"GND"
CDS_LIB"logical_power";
"A"12;
%"UNIVERSAL_GND"
"1","(1050,2700)","0","logical_power","I62";
;
HDL_POWER"GND"
CDS_LIB"logical_power";
"A"13;
%"VCCAUX15"
"1","(1050,3450)","0","logical_power","I64";
;
HDL_POWER"P3V3_AUX"
CDS_LIB"logical_power";
"A"4;
%"VCCAUX15"
"1","(3000,2400)","0","logical_power","I67";
;
HDL_POWER"P1V8_AUX"
CDS_LIB"logical_power";
"A"3;
%"VCCAUX15"
"1","(-725,2025)","0","logical_power","I89";
;
HDL_POWER"P3V3_AUX"
CDS_LIB"logical_power";
"A"1;
%"RT9059GQW"
"1","(0,2125)","0","pure_quanta","I96";
;
MATERIAL"IC"
PART_TYPE"SMLF"
VALUE"RT9059GQW"
PART_NUMBER"AL009059000"
PIN_NAMES_ROTATE"True"
CDS_LIB"pure_quanta"
CDS_LMAN_SYM_OUTLINE"-250,550,250,-550"
LOCATION"U41"
$SEC"1"
CDS_SEC"1";
"VIN3"
$PN"9"4;
"VIN2"
$PN"8"4;
"VOUT3"
$PN"3"3;
"VOUT2"
$PN"2"3;
"EP"
$PN"TH"10;
"VDD"
$PN"10"5;
"VIN1"
$PN"7"4;
"VOUT1"
$PN"1"3;
"ADJ"
$PN"4"24;
"EN"
$PN"6"14;
"PGOOD"
$PN"5"17;
%"Q_RES"
"2","(975,1575)","0","pure_quanta","I97";
;
PACK_TYPE"0402LF"
TOLERANCE"1%"
VALUE"12K"
WATTAGE"1/16W"
MATERIAL"CHIP"
PART_NUMBER"CS31202FB04"
CDS_LIB"pure_quanta"
LOCATION"R832"
$SEC"1"
CDS_SEC"1";
"A"
$PN"1"24;
"B"
$PN"2"10;
%"Q_RES"
"2","(975,2000)","0","pure_quanta","I98";
;
VALUE"15K"
PACK_TYPE"0402LF"
PART_NUMBER"CS31502FB05"
MATERIAL"CHIP"
WATTAGE"1/16W"
TOLERANCE"1%"
CDS_LIB"pure_quanta"
LOCATION"R831"
$SEC"1"
CDS_SEC"1";
"A"
$PN"1"3;
"B"
$PN"2"24;
%"Q_RES"
"1","(-2025,1625)","0","pure_quanta","I99";
;
VALUE"0"
MATERIAL"CHIP"
PACK_TYPE"0402LF"
PART_NUMBER"CS00002JB13"
CDS_LIB"pure_quanta"
WATTAGE"1/16W"
TOLERANCE"5%"
LOCATION"R275"
$SEC"1"
CDS_SEC"1";
"B"
$PN"2"17;
"A"
$PN"1"21;
END.
